(kicad_pcb
	(version 20260206)
	(generator "pcbnew")
	(generator_version "10.0")
	(general
		(thickness 1.6)
		(legacy_teardrops no)
	)
	(paper "A4")
	(title_block
		(title "Wiwynn_Tioga_Pass_MB.brd")
		(comment 1 "Tioga Pass / footprints 1031-1032 of 4770")
	)
	(layers
		(0 "F.Cu" signal "TOP")
		(4 "In1.Cu" signal "L2GND")
		(6 "In2.Cu" signal "L3")
		(8 "In3.Cu" signal "L4GND")
		(10 "In4.Cu" signal "L5")
		(12 "In5.Cu" signal "L6GND")
		(14 "In6.Cu" signal "L7VCC")
		(16 "In7.Cu" signal "L8VCC")
		(18 "In8.Cu" signal "L9GND")
		(20 "In9.Cu" signal "L10")
		(22 "In10.Cu" signal "L11GND")
		(24 "In11.Cu" signal "L12")
		(26 "In12.Cu" signal "L13GND")
		(2 "B.Cu" signal "BOTTOM")
		(9 "F.Adhes" user "F.Adhesive")
		(11 "B.Adhes" user "B.Adhesive")
		(13 "F.Paste" user "Package Geometry/Pastemask Top")
		(15 "B.Paste" user "Package Geometry/Pastemask Bottom")
		(5 "F.SilkS" user "Ref Des/Silkscreen Top")
		(7 "B.SilkS" user "Ref Des/Silkscreen Bottom")
		(1 "F.Mask" user "Board Geometry/Soldermask Top")
		(3 "B.Mask" user "Board Geometry/Soldermask Bottom")
		(17 "Dwgs.User" user "User.Drawings")
		(19 "Cmts.User" user "User.Comments")
		(21 "Eco1.User" user "User.Eco1")
		(23 "Eco2.User" user "User.Eco2")
		(25 "Edge.Cuts" user "Board Geometry/Outline")
		(27 "Margin" user)
		(31 "F.CrtYd" user "Package Geometry/Place Bound Top")
		(29 "B.CrtYd" user "Package Geometry/Place Bound Bottom")
		(35 "F.Fab" user "Ref Des/Assembly Top")
		(33 "B.Fab" user "Ref Des/Assembly Bottom")
	)
	(footprint ""
		(layer "F.Cu")
		(at 316.3443 -164.9095 -90)
		(property "Reference" "T1D19"
			(at 0 0 270)
			(layer "F.SilkS")
			(hide yes)
			(effects
				(font
					(size 1.27 1.27)
				)
			)
		)
		(property "Value" "*"
			(at -3.4036 -4.46405 270)
			(unlocked yes)
			(layer "F.Fab")
			(hide yes)
			(effects
				(font
					(size 0.889 0.889)
					(thickness 0.1524)
				)
			)
		)
		(property "Device Type" "TEST-PAD-12P-1-GP-U_DISCRET-GBA"
			(at -3.4036 -5.98805 270)
			(unlocked yes)
			(layer "F.Fab")
			(hide yes)
			(effects
				(font
					(size 0.889 0.889)
					(thickness 0.1524)
				)
			)
		)
		(duplicate_pad_numbers_are_jumpers no)
		(fp_line
			(start -2.3876 3.4798)
			(end -2.3876 -4.826)
			(stroke
				(width 0.1524)
				(type default)
			)
			(layer "F.SilkS")
		)
		(fp_line
			(start 2.3622 3.4798)
			(end -2.3876 3.4798)
			(stroke
				(width 0.1524)
				(type default)
			)
			(layer "F.SilkS")
		)
		(fp_line
			(start -2.3876 -4.826)
			(end 2.3622 -4.826)
			(stroke
				(width 0.1524)
				(type default)
			)
			(layer "F.SilkS")
		)
		(fp_line
			(start 2.3622 -4.826)
			(end 2.3622 3.4798)
			(stroke
				(width 0.1524)
				(type default)
			)
			(layer "F.SilkS")
		)
		(fp_rect
			(start -2.6416 3.7338)
			(end 2.6162 -5.08)
			(stroke
				(width 0)
				(type default)
			)
			(fill no)
			(layer "F.CrtYd")
		)
		(fp_rect
			(start -2.6416 3.7338)
			(end 2.6162 -5.08)
			(stroke
				(width 0)
				(type default)
			)
			(fill no)
			(layer "F.Fab")
		)
		(pad "1" smd circle
			(at 0.496824 -1.301496 270)
			(size 0.6604 0.6604)
			(layers "F.Cu" "F.Mask" "F.Paste")
			(net "L10_85OHM_10INCH_DP")
		)
		(pad "2" smd circle
			(at -0.503936 -1.301496 270)
			(size 0.6604 0.6604)
			(layers "F.Cu" "F.Mask" "F.Paste")
			(net "L10_85OHM_10INCH_DN")
		)
		(pad "3" smd custom
			(at -0.00889 0.370078 270)
			(size 0.74295 0.74295)
			(layers "F.Cu" "F.Mask" "F.Paste")
			(net "GND")
			(options
				(clearance outline)
				(anchor circle)
			)
			(primitives
				(gr_poly
					(pts
						(xy -2.1209 1.4859) (xy 2.1209 1.4859) (xy 2.1209 -1.4859) (xy 1.08585 -1.4859) (xy 1.08585 -0.4699)
						(xy -1.08585 -0.4699) (xy -1.08585 -1.4859) (xy -2.1209 -1.4859)
					)
					(width 0)
					(fill yes)
				)
			)
		)
		(pad "4" thru_hole circle
			(at 1.266444 -3.851656 270)
			(size 1.4478 1.4478)
			(drill 1.0414)
			(layers "*.Cu" "*.Mask")
			(remove_unused_layers no)
			(net "GND")
			(clearance 0.1524)
			(thermal_gap 0.1524)
		)
		(pad "5" thru_hole circle
			(at -1.273556 -3.851656 270)
			(size 1.4478 1.4478)
			(drill 1.0414)
			(layers "*.Cu" "*.Mask")
			(remove_unused_layers no)
			(net "GND")
			(clearance 0.1524)
			(thermal_gap 0.1524)
		)
		(pad "6" thru_hole circle
			(at 1.266444 2.498344 270)
			(size 1.4478 1.4478)
			(drill 1.0414)
			(layers "*.Cu" "*.Mask")
			(remove_unused_layers no)
			(net "GND")
			(clearance 0.1524)
			(thermal_gap 0.1524)
		)
		(pad "7" thru_hole circle
			(at -1.273556 2.498344 270)
			(size 1.4478 1.4478)
			(drill 1.0414)
			(layers "*.Cu" "*.Mask")
			(remove_unused_layers no)
			(net "GND")
			(clearance 0.1524)
			(thermal_gap 0.1524)
		)
		(pad "8" thru_hole circle
			(at 1.27 -0.4572 270)
			(size 0.7112 0.7112)
			(drill 0.4064)
			(layers "*.Cu" "*.Mask")
			(remove_unused_layers no)
			(net "GND")
			(clearance 0.1016)
			(thermal_gap 0.1016)
		)
		(pad "9" thru_hole circle
			(at 1.27 0.762 270)
			(size 0.7112 0.7112)
			(drill 0.4064)
			(layers "*.Cu" "*.Mask")
			(remove_unused_layers no)
			(net "GND")
			(clearance 0.1016)
			(thermal_gap 0.1016)
		)
		(pad "10" thru_hole circle
			(at -0.0254 0.762 270)
			(size 0.7112 0.7112)
			(drill 0.4064)
			(layers "*.Cu" "*.Mask")
			(remove_unused_layers no)
			(net "GND")
			(clearance 0.1016)
			(thermal_gap 0.1016)
		)
		(pad "11" thru_hole circle
			(at -1.27 0.762 270)
			(size 0.7112 0.7112)
			(drill 0.4064)
			(layers "*.Cu" "*.Mask")
			(remove_unused_layers no)
			(net "GND")
			(clearance 0.1016)
			(thermal_gap 0.1016)
		)
		(pad "12" thru_hole circle
			(at -1.27 -0.4572 270)
			(size 0.7112 0.7112)
			(drill 0.4064)
			(layers "*.Cu" "*.Mask")
			(remove_unused_layers no)
			(net "GND")
			(clearance 0.1016)
			(thermal_gap 0.1016)
		)
	)
	(footprint ""
		(layer "F.Cu")
		(at 176.437798 -17.65681 90)
		(property "Reference" "R4F6"
			(at 0 0 90)
			(layer "F.SilkS")
			(hide yes)
			(effects
				(font
					(size 1.27 1.27)
				)
			)
		)
		(property "Value" ""
			(at 0 0 90)
			(layer "F.Fab")
			(effects
				(font
					(size 1.27 1.27)
				)
			)
		)
		(duplicate_pad_numbers_are_jumpers no)
		(fp_rect
			(start -0.2794 -0.1016)
			(end 0.2794 0.9906)
			(stroke
				(width 0)
				(type default)
			)
			(fill no)
			(layer "F.CrtYd")
		)
		(fp_line
			(start 0.2794 -0.1016)
			(end -0.2794 -0.1016)
			(stroke
				(width 0.1)
				(type default)
			)
			(layer "F.Fab")
		)
		(fp_line
			(start -0.2794 -0.1016)
			(end -0.2794 0.9906)
			(stroke
				(width 0.1)
				(type default)
			)
			(layer "F.Fab")
		)
		(fp_line
			(start 0.2794 0.9906)
			(end 0.2794 -0.1016)
			(stroke
				(width 0.1)
				(type default)
			)
			(layer "F.Fab")
		)
		(fp_line
			(start -0.2794 0.9906)
			(end 0.2794 0.9906)
			(stroke
				(width 0.1)
				(type default)
			)
			(layer "F.Fab")
		)
		(pad "1" smd rect
			(at 0 0 90)
			(size 0.508 0.508)
			(layers "F.Cu" "F.Mask" "F.Paste")
			(net "VR_PVPP_GHJ_SNUB")
		)
		(pad "2" smd rect
			(at 0 0.889 90)
			(size 0.508 0.508)
			(layers "F.Cu" "F.Mask" "F.Paste")
			(net "GND")
		)
		(zone
			(layer "F.Cu")
			(hatch none 0.5)
			(connect_pads
				(clearance 0)
			)
			(min_thickness 0.25)
			(keepout
				(tracks allowed)
				(vias not_allowed)
				(pads allowed)
				(copperpour not_allowed)
				(footprints allowed)
			)
			(placement
				(enabled no)
				(sheetname "")
			)
			(fill
				(thermal_gap 0.5)
				(thermal_bridge_width 0.5)
				(island_removal_mode 0)
			)
			(polygon
				(pts
					(xy 176.691798 -17.40281) (xy 177.072798 -17.40281) (xy 177.072798 -17.91081) (xy 176.691798 -17.91081)
				)
			)
		)
		(zone
			(layer "F.Cu")
			(hatch none 0.5)
			(connect_pads
				(clearance 0)
			)
			(min_thickness 0.25)
			(keepout
				(tracks not_allowed)
				(vias allowed)
				(pads allowed)
				(copperpour not_allowed)
				(footprints allowed)
			)
			(placement
				(enabled no)
				(sheetname "")
			)
			(fill
				(thermal_gap 0.5)
				(thermal_bridge_width 0.5)
				(island_removal_mode 0)
			)
			(polygon
				(pts
					(xy 176.691798 -17.40281) (xy 177.072798 -17.40281) (xy 177.072798 -17.91081) (xy 176.691798 -17.91081)
				)
			)
		)
	)
)
